# BASEBOARD_FAB2 (Tioga Pass) — schematic netlist excerpt (pin names and nets, part order shuffled) for the footprints in the layout excerpt that follows; sources: Cadence DE-HDL packaged netlist, KiCad conversion of Wiwynn_Tioga_Pass_MB.brd

FB4G1  FERRITE  22 1% FB  pkg SM  page 233 : A = P12V_STBY ; B = VR_FET_SW_P12V_STBY_PVPP_GHJ
C2D17  CAP_A  22.0UF 4V 20% X6S  pkg 0603V  page 76 : A = PVCCIN_CPU1 ; B = GND
C826  CAP  0.22UF 16V 10% X7R  pkg 0402  page 244 : A = P3E_CPU0_PE1_PCH_TXN<14> ; B = P3E_CPU0_PE1_PCH_CON_TXN<14>

(kicad_pcb
	(version 20260206)
	(generator "pcbnew")
	(generator_version "10.0")
	(general
		(thickness 1.6)
		(legacy_teardrops no)
	)
	(paper "A4")
	(title_block
		(title "Wiwynn_Tioga_Pass_MB.brd")
		(comment 1 "Tioga Pass / footprints 873-875 of 4770")
	)
	(layers
		(0 "F.Cu" signal "TOP")
		(4 "In1.Cu" signal "L2GND")
		(6 "In2.Cu" signal "L3")
		(8 "In3.Cu" signal "L4GND")
		(10 "In4.Cu" signal "L5")
		(12 "In5.Cu" signal "L6GND")
		(14 "In6.Cu" signal "L7VCC")
		(16 "In7.Cu" signal "L8VCC")
		(18 "In8.Cu" signal "L9GND")
		(20 "In9.Cu" signal "L10")
		(22 "In10.Cu" signal "L11GND")
		(24 "In11.Cu" signal "L12")
		(26 "In12.Cu" signal "L13GND")
		(2 "B.Cu" signal "BOTTOM")
		(9 "F.Adhes" user "F.Adhesive")
		(11 "B.Adhes" user "B.Adhesive")
		(13 "F.Paste" user "Package Geometry/Pastemask Top")
		(15 "B.Paste" user "Package Geometry/Pastemask Bottom")
		(5 "F.SilkS" user "Ref Des/Silkscreen Top")
		(7 "B.SilkS" user "Ref Des/Silkscreen Bottom")
		(1 "F.Mask" user "Board Geometry/Soldermask Top")
		(3 "B.Mask" user "Board Geometry/Soldermask Bottom")
		(17 "Dwgs.User" user "User.Drawings")
		(19 "Cmts.User" user "User.Comments")
		(21 "Eco1.User" user "User.Eco1")
		(23 "Eco2.User" user "User.Eco2")
		(25 "Edge.Cuts" user "Board Geometry/Outline")
		(27 "Margin" user)
		(31 "F.CrtYd" user "Package Geometry/Place Bound Top")
		(29 "B.CrtYd" user "Package Geometry/Place Bound Bottom")
		(35 "F.Fab" user "Ref Des/Assembly Top")
		(33 "B.Fab" user "Ref Des/Assembly Bottom")
	)
	(footprint ""
		(layer "F.Cu")
		(at 103.172768 -79.6036 180)
		(property "Reference" "C2D17"
			(at 0 0 180)
			(layer "F.SilkS")
			(hide yes)
			(effects
				(font
					(size 1.27 1.27)
				)
			)
		)
		(property "Value" ""
			(at 0 0 180)
			(layer "F.Fab")
			(effects
				(font
					(size 1.27 1.27)
				)
			)
		)
		(duplicate_pad_numbers_are_jumpers no)
		(fp_poly
			(pts
				(xy -0.4953 -0.2032) (xy 0.4953 -0.2032) (xy 0.4953 1.6002) (xy -0.4953 1.6002)
			)
			(stroke
				(width 0)
				(type default)
			)
			(fill no)
			(layer "F.CrtYd")
		)
		(fp_line
			(start 0.4953 1.6002)
			(end -0.4953 1.6002)
			(stroke
				(width 0.1)
				(type default)
			)
			(layer "F.Fab")
		)
		(fp_line
			(start 0.4953 -0.2032)
			(end 0.4953 1.6002)
			(stroke
				(width 0.1)
				(type default)
			)
			(layer "F.Fab")
		)
		(fp_line
			(start -0.4953 1.6002)
			(end -0.4953 -0.2032)
			(stroke
				(width 0.1)
				(type default)
			)
			(layer "F.Fab")
		)
		(fp_line
			(start -0.4953 -0.2032)
			(end 0.4953 -0.2032)
			(stroke
				(width 0.1)
				(type default)
			)
			(layer "F.Fab")
		)
		(pad "1" smd rect
			(at 0 0 180)
			(size 0.762 0.889)
			(layers "F.Cu" "F.Mask" "F.Paste")
			(net "PVCCIN_CPU1")
		)
		(pad "2" smd rect
			(at 0 1.397 180)
			(size 0.762 0.889)
			(layers "F.Cu" "F.Mask" "F.Paste")
			(net "GND")
		)
		(zone
			(layer "F.Cu")
			(hatch none 0.5)
			(connect_pads
				(clearance 0)
			)
			(min_thickness 0.25)
			(keepout
				(tracks not_allowed)
				(vias allowed)
				(pads allowed)
				(copperpour not_allowed)
				(footprints allowed)
			)
			(placement
				(enabled no)
				(sheetname "")
			)
			(fill
				(thermal_gap 0.5)
				(thermal_bridge_width 0.5)
				(island_removal_mode 0)
			)
			(polygon
				(pts
					(xy 103.553768 -80.0481) (xy 102.791768 -80.0481) (xy 102.791768 -80.5561) (xy 103.553768 -80.5561)
				)
			)
		)
	)
	(footprint ""
		(layer "F.Cu")
		(at 324.5485 -123.825 -90)
		(property "Reference" "C826"
			(at -0.8382 -0.67818 270)
			(unlocked yes)
			(layer "F.SilkS")
			(effects
				(font
					(size 0.4064 0.254)
					(thickness 0.1524)
				)
				(justify left)
			)
		)
		(property "Value" ""
			(at 0 0 270)
			(layer "F.Fab")
			(effects
				(font
					(size 1.27 1.27)
				)
			)
		)
		(duplicate_pad_numbers_are_jumpers no)
		(fp_poly
			(pts
				(xy 0.3048 -0.1016) (xy 0.3048 0.9906) (xy -0.3048 0.9906) (xy -0.3048 -0.1016)
			)
			(stroke
				(width 0)
				(type default)
			)
			(fill no)
			(layer "F.CrtYd")
		)
		(fp_line
			(start -0.3048 0.9906)
			(end 0.3048 0.9906)
			(stroke
				(width 0.1)
				(type default)
			)
			(layer "F.Fab")
		)
		(fp_line
			(start 0.3048 0.9906)
			(end 0.3048 -0.1016)
			(stroke
				(width 0.1)
				(type default)
			)
			(layer "F.Fab")
		)
		(fp_line
			(start -0.3048 -0.1016)
			(end -0.3048 0.9906)
			(stroke
				(width 0.1)
				(type default)
			)
			(layer "F.Fab")
		)
		(fp_line
			(start 0.3048 -0.1016)
			(end -0.3048 -0.1016)
			(stroke
				(width 0.1)
				(type default)
			)
			(layer "F.Fab")
		)
		(pad "1" smd rect
			(at 0 0 270)
			(size 0.508 0.508)
			(layers "F.Cu" "F.Mask" "F.Paste")
			(net "P3E_CPU0_PE1_PCH_TXN<14>")
		)
		(pad "2" smd rect
			(at 0 0.889 270)
			(size 0.508 0.508)
			(layers "F.Cu" "F.Mask" "F.Paste")
			(net "P3E_CPU0_PE1_PCH_CON_TXN<14>")
		)
		(zone
			(layer "F.Cu")
			(hatch none 0.5)
			(connect_pads
				(clearance 0)
			)
			(min_thickness 0.25)
			(keepout
				(tracks not_allowed)
				(vias allowed)
				(pads allowed)
				(copperpour not_allowed)
				(footprints allowed)
			)
			(placement
				(enabled no)
				(sheetname "")
			)
			(fill
				(thermal_gap 0.5)
				(thermal_bridge_width 0.5)
				(island_removal_mode 0)
			)
			(polygon
				(pts
					(xy 323.9135 -124.079) (xy 323.9135 -123.571) (xy 324.2945 -123.571) (xy 324.2945 -124.079)
				)
			)
		)
		(zone
			(layer "F.Cu")
			(hatch none 0.5)
			(connect_pads
				(clearance 0)
			)
			(min_thickness 0.25)
			(keepout
				(tracks allowed)
				(vias not_allowed)
				(pads allowed)
				(copperpour not_allowed)
				(footprints allowed)
			)
			(placement
				(enabled no)
				(sheetname "")
			)
			(fill
				(thermal_gap 0.5)
				(thermal_bridge_width 0.5)
				(island_removal_mode 0)
			)
			(polygon
				(pts
					(xy 324.2945 -124.079) (xy 324.2945 -123.571) (xy 323.9135 -123.571) (xy 323.9135 -124.079)
				)
			)
		)
	)
	(footprint ""
		(layer "F.Cu")
		(at 185.166 -15.113)
		(property "Reference" "FB4G1"
			(at 0 0 0)
			(layer "F.SilkS")
			(hide yes)
			(effects
				(font
					(size 1.27 1.27)
				)
			)
		)
		(property "Value" ""
			(at 0 0 0)
			(layer "F.Fab")
			(effects
				(font
					(size 1.27 1.27)
				)
			)
		)
		(duplicate_pad_numbers_are_jumpers no)
		(fp_rect
			(start -0.7239 2.03835)
			(end 0.7239 -0.26035)
			(stroke
				(width 0)
				(type default)
			)
			(fill no)
			(layer "F.CrtYd")
		)
		(fp_line
			(start -0.7239 -0.26035)
			(end 0.7239 -0.26035)
			(stroke
				(width 0.1)
				(type default)
			)
			(layer "F.Fab")
		)
		(fp_line
			(start -0.7239 2.03835)
			(end -0.7239 -0.26035)
			(stroke
				(width 0.1)
				(type default)
			)
			(layer "F.Fab")
		)
		(fp_line
			(start 0.7239 -0.26035)
			(end 0.7239 2.03835)
			(stroke
				(width 0.1)
				(type default)
			)
			(layer "F.Fab")
		)
		(fp_line
			(start 0.7239 2.03835)
			(end -0.7239 2.03835)
			(stroke
				(width 0.1)
				(type default)
			)
			(layer "F.Fab")
		)
		(pad "1" smd rect
			(at 0 0)
			(size 1.27 1.016)
			(layers "F.Cu" "F.Mask" "F.Paste")
			(net "P12V_STBY")
		)
		(pad "2" smd rect
			(at 0 1.778)
			(size 1.27 1.016)
			(layers "F.Cu" "F.Mask" "F.Paste")
			(net "VR_FET_SW_P12V_STBY_PVPP_GHJ")
		)
		(zone
			(layer "F.Cu")
			(hatch none 0.5)
			(connect_pads
				(clearance 0)
			)
			(min_thickness 0.25)
			(keepout
				(tracks not_allowed)
				(vias allowed)
				(pads allowed)
				(copperpour not_allowed)
				(footprints allowed)
			)
			(placement
				(enabled no)
				(sheetname "")
			)
			(fill
				(thermal_gap 0.5)
				(thermal_bridge_width 0.5)
				(island_removal_mode 0)
			)
			(polygon
				(pts
					(xy 185.801 -14.605) (xy 185.801 -13.843) (xy 185.7121 -13.843) (xy 184.531 -13.843) (xy 184.531 -14.605)
				)
			)
		)
	)
)
